(kicad_pcb
	(version 20240108)
	(generator "pcbnew")
	(generator_version "8.0")
	(general
		(thickness 1.62)
		(legacy_teardrops no)
	)
	(paper "A4")
	(title_block
		(title "Jetson Orin Baseboard")
		(date "2025-03-12")
		(rev "1.3.4")
		(company "Antmicro Ltd")
		(comment 1 "www.antmicro.com")
		(comment 9 "footprints 372-376 of 677")
	)
	(layers
		(0 "F.Cu" signal)
		(1 "In1.Cu" signal)
		(2 "In2.Cu" signal)
		(3 "In3.Cu" signal)
		(4 "In4.Cu" jumper)
		(5 "In5.Cu" signal)
		(6 "In6.Cu" signal)
		(31 "B.Cu" signal)
		(32 "B.Adhes" user "B.Adhesive")
		(33 "F.Adhes" user "F.Adhesive")
		(34 "B.Paste" user)
		(35 "F.Paste" user)
		(36 "B.SilkS" user "B.Silkscreen")
		(37 "F.SilkS" user "F.Silkscreen")
		(38 "B.Mask" user)
		(39 "F.Mask" user)
		(40 "Dwgs.User" user "User.Drawings")
		(41 "Cmts.User" user "User.Comments")
		(42 "Eco1.User" user "User.Eco1")
		(43 "Eco2.User" user "User.Eco2")
		(44 "Edge.Cuts" user)
		(45 "Margin" user)
		(46 "B.CrtYd" user "B.Courtyard")
		(47 "F.CrtYd" user "F.Courtyard")
		(48 "B.Fab" user)
		(49 "F.Fab" user)
	)
	(footprint "antmicro-footprints:R_0402_1005Metric"
		(layer "B.Cu")
		(at 130.6 93.2 90)
		(descr "Resistor SMD 0402")
		(tags "resistor SMD 0402")
		(property "Reference" "R134"
			(at 3.78 0.44 -90)
			(layer "B.SilkS")
			(effects
				(font
					(size 0.7 0.7)
					(thickness 0.15)
				)
				(justify left bottom mirror)
			)
		)
		(property "Value" "R_0R_0402"
			(at 0 -1.4 -90)
			(layer "B.Fab")
			(effects
				(font
					(size 0.7 0.7)
					(thickness 0.15)
				)
				(justify left bottom mirror)
			)
		)
		(property "Footprint" "antmicro-footprints:R_0402_1005Metric"
			(at 0 0 90)
			(layer "F.Fab")
			(hide yes)
			(effects
				(font
					(size 1.27 1.27)
					(thickness 0.15)
				)
			)
		)
		(property "Datasheet" "https://industrial.panasonic.com/cdbs/www-data/pdf/RDA0000/AOA0000C301.pdf"
			(at 0 0 90)
			(layer "F.Fab")
			(hide yes)
			(effects
				(font
					(size 1.27 1.27)
					(thickness 0.15)
				)
			)
		)
		(property "Author" "Antmicro"
			(at 223.8 -37.4 0)
			(layer "B.Fab")
			(hide yes)
			(effects
				(font
					(size 1 1)
					(thickness 0.15)
				)
				(justify mirror)
			)
		)
		(property "Current" "1A"
			(at 223.8 -37.4 0)
			(layer "B.Fab")
			(hide yes)
			(effects
				(font
					(size 1 1)
					(thickness 0.15)
				)
				(justify mirror)
			)
		)
		(property "License" "Apache-2.0"
			(at 223.8 -37.4 0)
			(layer "B.Fab")
			(hide yes)
			(effects
				(font
					(size 1 1)
					(thickness 0.15)
				)
				(justify mirror)
			)
		)
		(property "MPN" "ERJ2GE0R00X"
			(at 223.8 -37.4 0)
			(layer "B.Fab")
			(hide yes)
			(effects
				(font
					(size 1 1)
					(thickness 0.15)
				)
				(justify mirror)
			)
		)
		(property "Manufacturer" "Panasonic"
			(at 223.8 -37.4 0)
			(layer "B.Fab")
			(hide yes)
			(effects
				(font
					(size 1 1)
					(thickness 0.15)
				)
				(justify mirror)
			)
		)
		(property "Tolerance" ""
			(at 223.8 -37.4 0)
			(layer "B.Fab")
			(hide yes)
			(effects
				(font
					(size 1 1)
					(thickness 0.15)
				)
				(justify mirror)
			)
		)
		(property "Val" "0R"
			(at 223.8 -37.4 0)
			(layer "B.Fab")
			(hide yes)
			(effects
				(font
					(size 1 1)
					(thickness 0.15)
				)
				(justify mirror)
			)
		)
		(sheetname "Peripherals")
		(sheetfile "peripherals.kicad_sch")
		(attr smd exclude_from_pos_files exclude_from_bom dnp)
		(fp_rect
			(start -0.925 0.47)
			(end 0.925 -0.47)
			(stroke
				(width 0.05)
				(type default)
			)
			(fill none)
			(layer "B.CrtYd")
		)
		(fp_rect
			(start -0.5 0.25)
			(end 0.5 -0.25)
			(stroke
				(width 0.15)
				(type solid)
			)
			(fill none)
			(layer "B.Fab")
		)
		(fp_text user "${REFERENCE}"
			(at -0.95 -3.168 -90)
			(layer "B.Fab")
			(hide yes)
			(effects
				(font
					(size 0.7 0.7)
					(thickness 0.15)
				)
				(justify left bottom mirror)
			)
		)
		(fp_text user "License: Apache-2.0"
			(at -0.95 -5.169 -90)
			(layer "B.Fab")
			(hide yes)
			(effects
				(font
					(size 0.7 0.7)
					(thickness 0.15)
				)
				(justify left bottom mirror)
			)
		)
		(fp_text user "Author: Antmicro"
			(at -0.95 -4.169 -90)
			(layer "B.Fab")
			(hide yes)
			(effects
				(font
					(size 0.7 0.7)
					(thickness 0.15)
				)
				(justify left bottom mirror)
			)
		)
		(pad "1" smd roundrect
			(at -0.48 0 90)
			(size 0.59 0.64)
			(layers "B.Cu" "B.Paste" "B.Mask")
			(roundrect_rratio 0.25)
			(net 618 "/Peripherals/USB_CONN_N")
			(pintype "passive")
		)
		(pad "2" smd roundrect
			(at 0.48 0 90)
			(size 0.59 0.64)
			(layers "B.Cu" "B.Paste" "B.Mask")
			(roundrect_rratio 0.25)
			(net 434 "USB1_D_N")
			(pintype "passive")
		)
	)
	(footprint "antmicro-footprints:TP_SMD_0.75mm"
		(layer "B.Cu")
		(at 59.69 102.41 -135)
		(property "Reference" "TP26"
			(at 1.152584 -1.421285 45)
			(layer "B.SilkS")
			(hide yes)
			(effects
				(font
					(size 0.7 0.7)
					(thickness 0.15)
				)
				(justify left bottom mirror)
			)
		)
		(property "Value" "TP_0.75mm_SMD"
			(at 0 -1.2 45)
			(layer "B.Fab")
			(effects
				(font
					(size 0.7 0.7)
					(thickness 0.15)
				)
				(justify left bottom mirror)
			)
		)
		(property "Footprint" "antmicro-footprints:TP_SMD_0.75mm"
			(at 0 0 -135)
			(layer "F.Fab")
			(hide yes)
			(effects
				(font
					(size 1.27 1.27)
					(thickness 0.15)
				)
			)
		)
		(property "Author" "Antmicro"
			(at 29.482398 217.032009 0)
			(layer "B.Fab")
			(hide yes)
			(effects
				(font
					(size 1 1)
					(thickness 0.15)
				)
				(justify mirror)
			)
		)
		(property "License" "Apache-2.0"
			(at 29.482398 217.032009 0)
			(layer "B.Fab")
			(hide yes)
			(effects
				(font
					(size 1 1)
					(thickness 0.15)
				)
				(justify mirror)
			)
		)
		(property "MPN" ""
			(at 29.482398 217.032009 0)
			(layer "B.Fab")
			(hide yes)
			(effects
				(font
					(size 1 1)
					(thickness 0.15)
				)
				(justify mirror)
			)
		)
		(property "Manufacturer" ""
			(at 29.482398 217.032009 0)
			(layer "B.Fab")
			(hide yes)
			(effects
				(font
					(size 1 1)
					(thickness 0.15)
				)
				(justify mirror)
			)
		)
		(sheetname "USB Debug, DP")
		(sheetfile "usb.kicad_sch")
		(attr exclude_from_pos_files exclude_from_bom)
		(fp_circle
			(center 0 0)
			(end 0.475 0)
			(stroke
				(width 0.05)
				(type default)
			)
			(fill none)
			(layer "B.CrtYd")
		)
		(fp_text user "${REFERENCE}"
			(at -0.4 -2.7 45)
			(layer "B.Fab")
			(hide yes)
			(effects
				(font
					(size 0.7 0.7)
					(thickness 0.15)
				)
				(justify left bottom mirror)
			)
		)
		(fp_text user "License: Apache-2.0"
			(at -0.4 -5.101 45)
			(layer "B.Fab")
			(hide yes)
			(effects
				(font
					(size 0.7 0.7)
					(thickness 0.15)
				)
				(justify left bottom mirror)
			)
		)
		(fp_text user "Author: Antmicro"
			(at -0.4 -3.901 45)
			(layer "B.Fab")
			(hide yes)
			(effects
				(font
					(size 0.7 0.7)
					(thickness 0.15)
				)
				(justify left bottom mirror)
			)
		)
		(pad "1" smd circle
			(at 0 0 225)
			(size 0.75 0.75)
			(layers "B.Cu" "B.Mask")
			(net 708 "/USB Debug, DP/~{PDC_I2C3_IRQ}")
			(pinfunction "1")
			(pintype "passive")
		)
	)
	(footprint "antmicro-footprints:TP_SMD_0.75mm"
		(layer "B.Cu")
		(at 68.165 123.07 180)
		(property "Reference" "TP54"
			(at -3.12 -0.47 0)
			(layer "B.SilkS")
			(hide yes)
			(effects
				(font
					(size 0.7 0.7)
					(thickness 0.15)
				)
				(justify left bottom mirror)
			)
		)
		(property "Value" "TP_0.75mm_SMD"
			(at 0 -1.2 0)
			(layer "B.Fab")
			(effects
				(font
					(size 0.7 0.7)
					(thickness 0.15)
				)
				(justify left bottom mirror)
			)
		)
		(property "Footprint" "antmicro-footprints:TP_SMD_0.75mm"
			(at 0 0 180)
			(layer "F.Fab")
			(hide yes)
			(effects
				(font
					(size 1.27 1.27)
					(thickness 0.15)
				)
			)
		)
		(property "Author" "Antmicro"
			(at 136.33 246.14 0)
			(layer "B.Fab")
			(hide yes)
			(effects
				(font
					(size 1 1)
					(thickness 0.15)
				)
				(justify mirror)
			)
		)
		(property "License" "Apache-2.0"
			(at 136.33 246.14 0)
			(layer "B.Fab")
			(hide yes)
			(effects
				(font
					(size 1 1)
					(thickness 0.15)
				)
				(justify mirror)
			)
		)
		(property "MPN" ""
			(at 136.33 246.14 0)
			(layer "B.Fab")
			(hide yes)
			(effects
				(font
					(size 1 1)
					(thickness 0.15)
				)
				(justify mirror)
			)
		)
		(property "Manufacturer" ""
			(at 136.33 246.14 0)
			(layer "B.Fab")
			(hide yes)
			(effects
				(font
					(size 1 1)
					(thickness 0.15)
				)
				(justify mirror)
			)
		)
		(sheetname "Supply")
		(sheetfile "supply.kicad_sch")
		(attr exclude_from_pos_files exclude_from_bom)
		(fp_circle
			(center 0 0)
			(end 0.475 0)
			(stroke
				(width 0.05)
				(type default)
			)
			(fill none)
			(layer "B.CrtYd")
		)
		(fp_text user "License: Apache-2.0"
			(at -0.4 -5.101 0)
			(layer "B.Fab")
			(hide yes)
			(effects
				(font
					(size 0.7 0.7)
					(thickness 0.15)
				)
				(justify left bottom mirror)
			)
		)
		(fp_text user "${REFERENCE}"
			(at -0.4 -2.7 0)
			(layer "B.Fab")
			(hide yes)
			(effects
				(font
					(size 0.7 0.7)
					(thickness 0.15)
				)
				(justify left bottom mirror)
			)
		)
		(fp_text user "Author: Antmicro"
			(at -0.4 -3.901 0)
			(layer "B.Fab")
			(hide yes)
			(effects
				(font
					(size 0.7 0.7)
					(thickness 0.15)
				)
				(justify left bottom mirror)
			)
		)
		(pad "1" smd circle
			(at 0 0 180)
			(size 0.75 0.75)
			(layers "B.Cu" "B.Mask")
			(net 87 "+3V3")
			(pinfunction "1")
			(pintype "passive")
		)
	)
	(footprint "antmicro-footprints:TP_SMD_0.75mm"
		(layer "B.Cu")
		(at 63.205 71.3)
		(property "Reference" "TP2"
			(at 2.5 0.385 180)
			(layer "B.SilkS")
			(effects
				(font
					(size 0.7 0.7)
					(thickness 0.15)
				)
				(justify left bottom mirror)
			)
		)
		(property "Value" "TP_0.75mm_SMD"
			(at 0 -1.2 180)
			(layer "B.Fab")
			(effects
				(font
					(size 0.7 0.7)
					(thickness 0.15)
				)
				(justify left bottom mirror)
			)
		)
		(property "Footprint" "antmicro-footprints:TP_SMD_0.75mm"
			(at 0 0 0)
			(layer "F.Fab")
			(hide yes)
			(effects
				(font
					(size 1.27 1.27)
					(thickness 0.15)
				)
			)
		)
		(property "Author" "Antmicro"
			(at 0 0 0)
			(layer "B.Fab")
			(hide yes)
			(effects
				(font
					(size 1 1)
					(thickness 0.15)
				)
				(justify mirror)
			)
		)
		(property "License" "Apache-2.0"
			(at 0 0 0)
			(layer "B.Fab")
			(hide yes)
			(effects
				(font
					(size 1 1)
					(thickness 0.15)
				)
				(justify mirror)
			)
		)
		(property "MPN" ""
			(at 0 0 0)
			(layer "B.Fab")
			(hide yes)
			(effects
				(font
					(size 1 1)
					(thickness 0.15)
				)
				(justify mirror)
			)
		)
		(property "Manufacturer" ""
			(at 0 0 0)
			(layer "B.Fab")
			(hide yes)
			(effects
				(font
					(size 1 1)
					(thickness 0.15)
				)
				(justify mirror)
			)
		)
		(sheetname "SoM")
		(sheetfile "som.kicad_sch")
		(attr exclude_from_pos_files exclude_from_bom)
		(fp_circle
			(center 0 0)
			(end 0.475 0)
			(stroke
				(width 0.05)
				(type default)
			)
			(fill none)
			(layer "B.CrtYd")
		)
		(fp_text user "License: Apache-2.0"
			(at -0.4 -5.101 180)
			(layer "B.Fab")
			(hide yes)
			(effects
				(font
					(size 0.7 0.7)
					(thickness 0.15)
				)
				(justify left bottom mirror)
			)
		)
		(fp_text user "Author: Antmicro"
			(at -0.4 -3.901 180)
			(layer "B.Fab")
			(hide yes)
			(effects
				(font
					(size 0.7 0.7)
					(thickness 0.15)
				)
				(justify left bottom mirror)
			)
		)
		(fp_text user "${REFERENCE}"
			(at -0.4 -2.7 180)
			(layer "B.Fab")
			(hide yes)
			(effects
				(font
					(size 0.7 0.7)
					(thickness 0.15)
				)
				(justify left bottom mirror)
			)
		)
		(pad "1" smd circle
			(at 0 0)
			(size 0.75 0.75)
			(layers "B.Cu" "B.Mask")
			(net 478 "/SoM/SLEEP{slash}~{WAKE}")
			(pinfunction "1")
			(pintype "passive")
		)
	)
	(footprint "antmicro-footprints:LED_0603_1608Metric_G"
		(layer "B.Cu")
		(at 79.1 105.45 90)
		(descr "LED SMD 0603 Green")
		(tags "LED SMD 0603 Green")
		(property "Reference" "D4"
			(at 1.2 -0.7 180)
			(layer "B.SilkS")
			(effects
				(font
					(size 0.7 0.7)
					(thickness 0.15)
				)
				(justify right bottom mirror)
			)
		)
		(property "Value" "LED_G_0603_LTST-C190GKT"
			(at -0.001 -1.599 90)
			(layer "B.Fab")
			(effects
				(font
					(size 0.7 0.7)
					(thickness 0.15)
				)
				(justify right bottom mirror)
			)
		)
		(property "Footprint" "antmicro-footprints:LED_0603_1608Metric_G"
			(at 0 0 90)
			(layer "F.Fab")
			(hide yes)
			(effects
				(font
					(size 1.27 1.27)
					(thickness 0.15)
				)
			)
		)
		(property "Datasheet" "https://media.digikey.com/pdf/Data%20Sheets/Lite-On%20PDFs/LTST-C190GKT.pdf"
			(at 0 0 90)
			(layer "F.Fab")
			(hide yes)
			(effects
				(font
					(size 1.27 1.27)
					(thickness 0.15)
				)
			)
		)
		(property "Author" "Antmicro"
			(at 184.55 26.35 0)
			(layer "B.Fab")
			(hide yes)
			(effects
				(font
					(size 1 1)
					(thickness 0.15)
				)
				(justify mirror)
			)
		)
		(property "Color" "Green"
			(at 184.55 26.35 0)
			(layer "B.Fab")
			(hide yes)
			(effects
				(font
					(size 1 1)
					(thickness 0.15)
				)
				(justify mirror)
			)
		)
		(property "License" "Apache-2.0"
			(at 184.55 26.35 0)
			(layer "B.Fab")
			(hide yes)
			(effects
				(font
					(size 1 1)
					(thickness 0.15)
				)
				(justify mirror)
			)
		)
		(property "MPN" "LTST-C190GKT"
			(at 184.55 26.35 0)
			(layer "B.Fab")
			(hide yes)
			(effects
				(font
					(size 1 1)
					(thickness 0.15)
				)
				(justify mirror)
			)
		)
		(property "Manufacturer" "Lite-On"
			(at 184.55 26.35 0)
			(layer "B.Fab")
			(hide yes)
			(effects
				(font
					(size 1 1)
					(thickness 0.15)
				)
				(justify mirror)
			)
		)
		(sheetname "USB Debug, DP")
		(sheetfile "usb.kicad_sch")
		(attr smd)
		(fp_line
			(start -0.22 -0.35)
			(end 0.22 -0.35)
			(stroke
				(width 0.15)
				(type solid)
			)
			(layer "B.SilkS")
		)
		(fp_line
			(start -1.18 -0.321)
			(end -1.18 0.319)
			(stroke
				(width 0.15)
				(type solid)
			)
			(layer "B.SilkS")
		)
		(fp_line
			(start -0.094672 -0.001008)
			(end 0.105328 -0.201008)
			(stroke
				(width 0.1)
				(type solid)
			)
			(layer "B.SilkS")
		)
		(fp_line
			(start -0.24 -0.001008)
			(end -0.094672 -0.001008)
			(stroke
				(width 0.1)
				(type solid)
			)
			(layer "B.SilkS")
		)
		(fp_line
			(start 0.24 -0.001)
			(end 0.105328 -0.001008)
			(stroke
				(width 0.1)
				(type solid)
			)
			(layer "B.SilkS")
		)
		(fp_line
			(start 0.105328 0.198992)
			(end 0.105328 -0.201008)
			(stroke
				(width 0.1)
				(type solid)
			)
			(layer "B.SilkS")
		)
		(fp_line
			(start 0.105328 0.198992)
			(end -0.094672 -0.001008)
			(stroke
				(width 0.1)
				(type solid)
			)
			(layer "B.SilkS")
		)
		(fp_line
			(start -0.094672 0.198992)
			(end -0.094672 -0.201008)
			(stroke
				(width 0.1)
				(type solid)
			)
			(layer "B.SilkS")
		)
		(fp_line
			(start -0.22 0.35)
			(end 0.22 0.35)
			(stroke
				(width 0.15)
				(type solid)
			)
			(layer "B.SilkS")
		)
		(fp_rect
			(start 1.25 -0.65)
			(end -1.25 0.65)
			(stroke
				(width 0.05)
				(type solid)
			)
			(fill none)
			(layer "B.CrtYd")
		)
		(fp_line
			(start 0.201 -0.2)
			(end -0.101 0)
			(stroke
				(width 0.15)
				(type solid)
			)
			(layer "B.Fab")
		)
		(fp_line
			(start -0.199 -0.1)
			(end -0.199 -0.2)
			(stroke
				(width 0.15)
				(type solid)
			)
			(layer "B.Fab")
		)
		(fp_line
			(start -0.199 -0.1)
			(end -0.199 0.202)
			(stroke
				(width 0.15)
				(type solid)
			)
			(layer "B.Fab")
		)
		(fp_line
			(start 0.201 0)
			(end 0.201 -0.2)
			(stroke
				(width 0.15)
				(type solid)
			)
			(layer "B.Fab")
		)
		(fp_line
			(start 0.201 0)
			(end 0.599 0)
			(stroke
				(width 0.15)
				(type solid)
			)
			(layer "B.Fab")
		)
		(fp_line
			(start -0.101 0)
			(end 0.201 0.202)
			(stroke
				(width 0.15)
				(type solid)
			)
			(layer "B.Fab")
		)
		(fp_line
			(start -0.597 0)
			(end -0.199 0)
			(stroke
				(width 0.15)
				(type solid)
			)
			(layer "B.Fab")
		)
		(fp_line
			(start 0.201 0.202)
			(end 0.201 0)
			(stroke
				(width 0.15)
				(type solid)
			)
			(layer "B.Fab")
		)
		(fp_rect
			(start 0.848 -0.4)
			(end -0.85 0.402)
			(stroke
				(width 0.15)
				(type solid)
			)
			(fill none)
			(layer "B.Fab")
		)
		(fp_text user "${REFERENCE}"
			(at -1.4224 -5.999 90)
			(layer "B.Fab")
			(hide yes)
			(effects
				(font
					(size 0.7 0.7)
					(thickness 0.15)
				)
				(justify right bottom mirror)
			)
		)
		(fp_text user "Author: Antmicro"
			(at -1.4224 -4.799 90)
			(layer "B.Fab")
			(hide yes)
			(effects
				(font
					(size 0.7 0.7)
					(thickness 0.15)
				)
				(justify right bottom mirror)
			)
		)
		(fp_text user "License: Apache-2.0"
			(at -1.4224 -3.599 90)
			(layer "B.Fab")
			(hide yes)
			(effects
				(font
					(size 0.7 0.7)
					(thickness 0.15)
				)
				(justify right bottom mirror)
			)
		)
		(pad "1" smd roundrect
			(at -0.7 0 270)
			(size 0.8 1)
			(layers "B.Cu" "B.Paste" "B.Mask")
			(roundrect_rratio 0.2)
			(net 1 "GND")
			(pinfunction "C")
			(pintype "passive")
		)
		(pad "2" smd roundrect
			(at 0.7 0 270)
			(size 0.8 1)
			(layers "B.Cu" "B.Paste" "B.Mask")
			(roundrect_rratio 0.2)
			(net 144 "Net-(D4-A)")
			(pinfunction "A")
			(pintype "passive")
		)
	)
)
